# S9S_MB_2U (Grand Teton) — schematic netlist excerpt (pin names and nets, part order shuffled) for the footprints in the layout excerpt that follows; sources: Cadence DE-HDL packaged netlist, KiCad conversion of 03242023_DA0F0TMBIJ0_F0T_Motherboard_J_brd_V01_OCP.brd

C266  Q_CAP  10UF 6.3V 20% X6S  pkg C0402  page 77 : A = PVCCIN_CPU1 ; B = GND

(kicad_pcb
	(version 20260206)
	(generator "pcbnew")
	(generator_version "10.0")
	(general
		(thickness 1.6)
		(legacy_teardrops no)
	)
	(paper "A4")
	(title_block
		(title "03242023_DA0F0TMBIJ0_F0T_Motherboard_J_brd_V01_OCP.brd")
		(comment 1 "Grand Teton / footprints 910-910 of 6105")
	)
	(layers
		(0 "F.Cu" signal "TOP")
		(4 "In1.Cu" signal "GND")
		(6 "In2.Cu" signal "IN1")
		(8 "In3.Cu" signal "GND1")
		(10 "In4.Cu" signal "IN2")
		(12 "In5.Cu" signal "GND2")
		(14 "In6.Cu" signal "IN3")
		(16 "In7.Cu" signal "GND3")
		(18 "In8.Cu" signal "VCC")
		(20 "In9.Cu" signal "VCC1")
		(22 "In10.Cu" signal "GND4")
		(24 "In11.Cu" signal "IN4")
		(26 "In12.Cu" signal "GND5")
		(28 "In13.Cu" signal "IN5")
		(30 "In14.Cu" signal "GND6")
		(32 "In15.Cu" signal "IN6")
		(34 "In16.Cu" signal "GND7")
		(2 "B.Cu" signal "BOTTOM")
		(9 "F.Adhes" user "F.Adhesive")
		(11 "B.Adhes" user "B.Adhesive")
		(13 "F.Paste" user "Package Geometry/Pastemask Top")
		(15 "B.Paste" user "Package Geometry/Pastemask Bottom")
		(5 "F.SilkS" user "Ref Des/Silkscreen Top")
		(7 "B.SilkS" user "Ref Des/Silkscreen Bottom")
		(1 "F.Mask" user "Board Geometry/Soldermask Top")
		(3 "B.Mask" user "Board Geometry/Soldermask Bottom")
		(17 "Dwgs.User" user "User.Drawings")
		(19 "Cmts.User" user "User.Comments")
		(21 "Eco1.User" user "User.Eco1")
		(23 "Eco2.User" user "User.Eco2")
		(25 "Edge.Cuts" user "Board Geometry/Outline")
		(27 "Margin" user)
		(31 "F.CrtYd" user "Package Geometry/Place Bound Top")
		(29 "B.CrtYd" user "Package Geometry/Place Bound Bottom")
		(35 "F.Fab" user "Ref Des/Assembly Top")
		(33 "B.Fab" user "Ref Des/Assembly Bottom")
	)
	(footprint ""
		(layer "F.Cu")
		(at 105.3084 -252.956568 -90)
		(property "Reference" "C266"
			(at 0 0 270)
			(layer "F.SilkS")
			(hide yes)
			(effects
				(font
					(size 1.27 1.27)
				)
			)
		)
		(property "Value" ""
			(at 0 0 270)
			(layer "F.Fab")
			(effects
				(font
					(size 1.27 1.27)
				)
			)
		)
		(duplicate_pad_numbers_are_jumpers no)
		(fp_line
			(start -0.7874 0.4064)
			(end -0.7874 -0.4064)
			(stroke
				(width 0.1524)
				(type default)
			)
			(layer "F.SilkS")
		)
		(fp_line
			(start 0.7874 0.4064)
			(end -0.7874 0.4064)
			(stroke
				(width 0.1524)
				(type default)
			)
			(layer "F.SilkS")
		)
		(fp_line
			(start -0.7874 -0.4064)
			(end 0.7874 -0.4064)
			(stroke
				(width 0.1524)
				(type default)
			)
			(layer "F.SilkS")
		)
		(fp_line
			(start 0.7874 -0.4064)
			(end 0.7874 0.4064)
			(stroke
				(width 0.1524)
				(type default)
			)
			(layer "F.SilkS")
		)
		(fp_line
			(start -0.67945 0.3048)
			(end -0.67945 -0.305054)
			(stroke
				(width 0.1)
				(type default)
			)
			(layer "F.Fab")
		)
		(fp_line
			(start -0.12065 0.3048)
			(end -0.67945 0.3048)
			(stroke
				(width 0.1)
				(type default)
			)
			(layer "F.Fab")
		)
		(fp_line
			(start 0.120396 0.3048)
			(end 0.120396 0.2794)
			(stroke
				(width 0.1)
				(type default)
			)
			(layer "F.Fab")
		)
		(fp_line
			(start 0.67945 0.3048)
			(end 0.120396 0.3048)
			(stroke
				(width 0.1)
				(type default)
			)
			(layer "F.Fab")
		)
		(fp_line
			(start -0.12065 0.2794)
			(end -0.12065 0.3048)
			(stroke
				(width 0.1)
				(type default)
			)
			(layer "F.Fab")
		)
		(fp_line
			(start 0.120396 0.2794)
			(end -0.12065 0.2794)
			(stroke
				(width 0.1)
				(type default)
			)
			(layer "F.Fab")
		)
		(fp_line
			(start -0.12065 -0.2794)
			(end 0.12065 -0.2794)
			(stroke
				(width 0.1)
				(type default)
			)
			(layer "F.Fab")
		)
		(fp_line
			(start 0.12065 -0.2794)
			(end 0.12065 -0.3048)
			(stroke
				(width 0.1)
				(type default)
			)
			(layer "F.Fab")
		)
		(fp_line
			(start 0.12065 -0.3048)
			(end 0.67945 -0.3048)
			(stroke
				(width 0.1)
				(type default)
			)
			(layer "F.Fab")
		)
		(fp_line
			(start 0.67945 -0.3048)
			(end 0.67945 0.3048)
			(stroke
				(width 0.1)
				(type default)
			)
			(layer "F.Fab")
		)
		(fp_line
			(start -0.67945 -0.305054)
			(end -0.12065 -0.305054)
			(stroke
				(width 0.1)
				(type default)
			)
			(layer "F.Fab")
		)
		(fp_line
			(start -0.12065 -0.305054)
			(end -0.12065 -0.2794)
			(stroke
				(width 0.1)
				(type default)
			)
			(layer "F.Fab")
		)
		(pad "1" smd circle
			(at -0.40005 0 270)
			(size 0 0)
			(layers "F.Cu" "F.Mask" "F.Paste")
			(net "PVCCIN_CPU1")
		)
		(pad "2" smd circle
			(at 0.40005 0 270)
			(size 0 0)
			(layers "F.Cu" "F.Mask" "F.Paste")
			(net "GND")
		)
	)
)
